FILE_TYPE = MULTI_PHYS_TABLE;

PART 'ISL80101IRAJZ_DFN10'
CLASS=IC

{========================================================================================}
:CLS_PN          = JEDEC_TYPE                  | ALT_SYMBOLS                                                     | DESCRIPTION                                             | CPN_STATUS ;
{========================================================================================}
 'G222-10136-01' = 'DFN11_118_P0197_TR057X071' | '(DFN11_118_P0197_TR057X071_VIA,DFN11_118_P0197_TR065X080_AWS)' | 'IC,ISL80101IRAJZ-T,LDO,1A,ADJ_REGULATOR,10 LD 3*3 DFN' | ''        

END_PART

END.

